# S9S_MB_2U (Grand Teton) — schematic netlist excerpt (pin names and nets, part order shuffled) for the footprints in the layout excerpt that follows; sources: Cadence DE-HDL packaged netlist, KiCad conversion of 03242023_DA0F0TMBIJ0_F0T_Motherboard_J_brd_V01_OCP.brd

U264  INA230AIRGTR  IC  pkg QFN16_THXI  page 172
  A1  = INA230_4_A1
  A0  = INA230_4_A0
  ALERT  = M2_0_P3V3_ADC_ALERT_R
  SDA  = SMB_INA230_4_3V3AUX_SDA_R1
  SCL  = SMB_INA230_4_3V3AUX_SCL_R1
  NC0  = NC_INA230_4_NC0
  NC1  = NC_INA230_4_NC1
  NC2  = NC_INA230_4_NC2
  VS  = P3V3_AUX
  GND  = GND
  \bus\  = P3V3
  \in-\  = VSENSE_P12V_INA230_4_INN
  \in+\  = VSENSE_P12V_INA230_4_INP
  NC3  = NC_INA230_4_NC3
  NC4  = NC_INA230_4_NC4
  NC5  = NC_INA230_4_NC5
  TH  = GND

(kicad_pcb
	(version 20260206)
	(generator "pcbnew")
	(generator_version "10.0")
	(general
		(thickness 1.6)
		(legacy_teardrops no)
	)
	(paper "A4")
	(title_block
		(title "03242023_DA0F0TMBIJ0_F0T_Motherboard_J_brd_V01_OCP.brd")
		(comment 1 "Grand Teton / footprints 815-815 of 6105")
	)
	(layers
		(0 "F.Cu" signal "TOP")
		(4 "In1.Cu" signal "GND")
		(6 "In2.Cu" signal "IN1")
		(8 "In3.Cu" signal "GND1")
		(10 "In4.Cu" signal "IN2")
		(12 "In5.Cu" signal "GND2")
		(14 "In6.Cu" signal "IN3")
		(16 "In7.Cu" signal "GND3")
		(18 "In8.Cu" signal "VCC")
		(20 "In9.Cu" signal "VCC1")
		(22 "In10.Cu" signal "GND4")
		(24 "In11.Cu" signal "IN4")
		(26 "In12.Cu" signal "GND5")
		(28 "In13.Cu" signal "IN5")
		(30 "In14.Cu" signal "GND6")
		(32 "In15.Cu" signal "IN6")
		(34 "In16.Cu" signal "GND7")
		(2 "B.Cu" signal "BOTTOM")
		(9 "F.Adhes" user "F.Adhesive")
		(11 "B.Adhes" user "B.Adhesive")
		(13 "F.Paste" user "Package Geometry/Pastemask Top")
		(15 "B.Paste" user "Package Geometry/Pastemask Bottom")
		(5 "F.SilkS" user "Ref Des/Silkscreen Top")
		(7 "B.SilkS" user "Ref Des/Silkscreen Bottom")
		(1 "F.Mask" user "Board Geometry/Soldermask Top")
		(3 "B.Mask" user "Board Geometry/Soldermask Bottom")
		(17 "Dwgs.User" user "User.Drawings")
		(19 "Cmts.User" user "User.Comments")
		(21 "Eco1.User" user "User.Eco1")
		(23 "Eco2.User" user "User.Eco2")
		(25 "Edge.Cuts" user "Board Geometry/Outline")
		(27 "Margin" user)
		(31 "F.CrtYd" user "Package Geometry/Place Bound Top")
		(29 "B.CrtYd" user "Package Geometry/Place Bound Bottom")
		(35 "F.Fab" user "Ref Des/Assembly Top")
		(33 "B.Fab" user "Ref Des/Assembly Bottom")
	)
	(footprint ""
		(layer "F.Cu")
		(at 152.693624 -52.318412)
		(property "Reference" "U264"
			(at 4.867656 -2.900426 0)
			(unlocked yes)
			(layer "F.SilkS")
			(effects
				(font
					(size 0.7874 0.5842)
					(thickness 0.1524)
				)
			)
		)
		(property "Value" ""
			(at 0 0 0)
			(layer "F.Fab")
			(effects
				(font
					(size 1.27 1.27)
				)
			)
		)
		(duplicate_pad_numbers_are_jumpers no)
		(fp_line
			(start -1.500124 -1.500124)
			(end -1.004062 -1.500124)
			(stroke
				(width 0.1524)
				(type default)
			)
			(layer "F.SilkS")
		)
		(fp_line
			(start -1.500124 -1.004062)
			(end -1.500124 -1.500124)
			(stroke
				(width 0.1524)
				(type default)
			)
			(layer "F.SilkS")
		)
		(fp_line
			(start -1.500124 1.500124)
			(end -1.500124 1.004062)
			(stroke
				(width 0.1524)
				(type default)
			)
			(layer "F.SilkS")
		)
		(fp_line
			(start -1.004062 1.500124)
			(end -1.500124 1.500124)
			(stroke
				(width 0.1524)
				(type default)
			)
			(layer "F.SilkS")
		)
		(fp_line
			(start 1.004062 -1.500124)
			(end 1.500124 -1.500124)
			(stroke
				(width 0.1524)
				(type default)
			)
			(layer "F.SilkS")
		)
		(fp_line
			(start 1.500124 -1.500124)
			(end 1.500124 -1.004062)
			(stroke
				(width 0.1524)
				(type default)
			)
			(layer "F.SilkS")
		)
		(fp_line
			(start 1.500124 1.004062)
			(end 1.500124 1.500124)
			(stroke
				(width 0.1524)
				(type default)
			)
			(layer "F.SilkS")
		)
		(fp_line
			(start 1.500124 1.500124)
			(end 1.004062 1.500124)
			(stroke
				(width 0.1524)
				(type default)
			)
			(layer "F.SilkS")
		)
		(fp_poly
			(pts
				(xy -2.196846 -1.60782) (xy -1.83769 -0.530352) (xy -2.915412 -0.889508)
			)
			(stroke
				(width 0)
				(type default)
			)
			(fill yes)
			(layer "F.SilkS")
		)
		(fp_line
			(start -1.500124 -1.500124)
			(end 1.500124 -1.500124)
			(stroke
				(width 0.1)
				(type default)
			)
			(layer "F.Fab")
		)
		(fp_line
			(start -1.500124 1.500124)
			(end -1.500124 -1.500124)
			(stroke
				(width 0.1)
				(type default)
			)
			(layer "F.Fab")
		)
		(fp_line
			(start 1.500124 -1.500124)
			(end 1.500124 1.500124)
			(stroke
				(width 0.1)
				(type default)
			)
			(layer "F.Fab")
		)
		(fp_line
			(start 1.500124 1.500124)
			(end -1.500124 1.500124)
			(stroke
				(width 0.1)
				(type default)
			)
			(layer "F.Fab")
		)
		(fp_poly
			(pts
				(xy -2.847848 -1.258062) (xy -2.847848 -0.242062) (xy -1.831848 -0.750062)
			)
			(stroke
				(width 0)
				(type default)
			)
			(fill yes)
			(layer "F.Fab")
		)
		(pad "1" smd rect
			(at -1.400048 -0.750062 270)
			(size 0.2286 0.6096)
			(layers "F.Cu" "F.Mask" "F.Paste")
			(net "INA230_4_A1")
		)
		(pad "2" smd rect
			(at -1.400048 -0.249936 270)
			(size 0.2286 0.6096)
			(layers "F.Cu" "F.Mask" "F.Paste")
			(net "INA230_4_A0")
		)
		(pad "3" smd rect
			(at -1.400048 0.249936 270)
			(size 0.2286 0.6096)
			(layers "F.Cu" "F.Mask" "F.Paste")
			(net "M2_0_P3V3_ADC_ALERT_R")
		)
		(pad "4" smd rect
			(at -1.400048 0.750062 270)
			(size 0.2286 0.6096)
			(layers "F.Cu" "F.Mask" "F.Paste")
			(net "SMB_INA230_4_3V3AUX_SDA_R1")
		)
		(pad "5" smd rect
			(at -0.750062 1.400048)
			(size 0.2286 0.6096)
			(layers "F.Cu" "F.Mask" "F.Paste")
			(net "SMB_INA230_4_3V3AUX_SCL_R1")
		)
		(pad "6" smd rect
			(at -0.249936 1.400048)
			(size 0.2286 0.6096)
			(layers "F.Cu" "F.Mask" "F.Paste")
			(net "NC_INA230_4_NC0")
		)
		(pad "7" smd rect
			(at 0.249936 1.400048)
			(size 0.2286 0.6096)
			(layers "F.Cu" "F.Mask" "F.Paste")
			(net "NC_INA230_4_NC1")
		)
		(pad "8" smd rect
			(at 0.750062 1.400048)
			(size 0.2286 0.6096)
			(layers "F.Cu" "F.Mask" "F.Paste")
			(net "NC_INA230_4_NC2")
		)
		(pad "9" smd rect
			(at 1.400048 0.750062 270)
			(size 0.2286 0.6096)
			(layers "F.Cu" "F.Mask" "F.Paste")
			(net "P3V3_AUX")
		)
		(pad "10" smd rect
			(at 1.400048 0.249936 270)
			(size 0.2286 0.6096)
			(layers "F.Cu" "F.Mask" "F.Paste")
			(net "GND")
		)
		(pad "11" smd rect
			(at 1.400048 -0.249936 270)
			(size 0.2286 0.6096)
			(layers "F.Cu" "F.Mask" "F.Paste")
			(net "P3V3")
		)
		(pad "12" smd rect
			(at 1.400048 -0.750062 270)
			(size 0.2286 0.6096)
			(layers "F.Cu" "F.Mask" "F.Paste")
			(net "VSENSE_P12V_INA230_4_INN")
		)
		(pad "13" smd rect
			(at 0.750062 -1.400048)
			(size 0.2286 0.6096)
			(layers "F.Cu" "F.Mask" "F.Paste")
			(net "VSENSE_P12V_INA230_4_INP")
		)
		(pad "14" smd rect
			(at 0.249936 -1.400048)
			(size 0.2286 0.6096)
			(layers "F.Cu" "F.Mask" "F.Paste")
			(net "NC_INA230_4_NC3")
		)
		(pad "15" smd rect
			(at -0.249936 -1.400048)
			(size 0.2286 0.6096)
			(layers "F.Cu" "F.Mask" "F.Paste")
			(net "NC_INA230_4_NC4")
		)
		(pad "16" smd rect
			(at -0.750062 -1.400048)
			(size 0.2286 0.6096)
			(layers "F.Cu" "F.Mask" "F.Paste")
			(net "NC_INA230_4_NC5")
		)
		(pad "TH" smd rect
			(at 0 0)
			(size 1.7018 1.7018)
			(layers "F.Cu" "F.Mask" "F.Paste")
			(net "GND")
		)
		(zone
			(layer "F.Cu")
			(hatch none 0.5)
			(connect_pads
				(clearance 0)
			)
			(min_thickness 0.25)
			(keepout
				(tracks not_allowed)
				(vias allowed)
				(pads allowed)
				(copperpour not_allowed)
				(footprints allowed)
			)
			(placement
				(enabled no)
				(sheetname "")
			)
			(fill
				(thermal_gap 0.5)
				(thermal_bridge_width 0.5)
				(island_removal_mode 0)
			)
			(polygon
				(pts
					(xy 151.649176 -52.343812) (xy 151.649176 -53.36286) (xy 153.738072 -53.36286) (xy 153.738072 -51.273964)
					(xy 151.649176 -51.273964) (xy 151.649176 -52.318412) (xy 151.791924 -52.318412) (xy 151.791924 -51.416712)
					(xy 153.595324 -51.416712) (xy 153.595324 -53.220112) (xy 151.791924 -53.220112) (xy 151.791924 -52.343812)
				)
			)
		)
	)
)
